# S9S_MB_2U (Grand Teton) — schematic netlist excerpt (pin names and nets, part order shuffled) for the footprints in the layout excerpt that follows; sources: Cadence DE-HDL packaged netlist, KiCad conversion of 03242023_DA0F0TMBIJ0_F0T_Motherboard_J_brd_V01_OCP.brd

R1330  Q_RES  2K 1% EMPTY  pkg 0402LF  page 219 : A = PWRGD_DRAMPWRGD_CPU1_CD_R_LVC1 ; B = GND
PC251_P0_5  Q_CAP  2.2UF 10V 10% X6S  pkg C0402  page 269 : A = PVCCIN_CPU0_PVCC ; B = GND

(kicad_pcb
	(version 20260206)
	(generator "pcbnew")
	(generator_version "10.0")
	(general
		(thickness 1.6)
		(legacy_teardrops no)
	)
	(paper "A4")
	(title_block
		(title "03242023_DA0F0TMBIJ0_F0T_Motherboard_J_brd_V01_OCP.brd")
		(comment 1 "Grand Teton / footprints 1138-1139 of 6105")
	)
	(layers
		(0 "F.Cu" signal "TOP")
		(4 "In1.Cu" signal "GND")
		(6 "In2.Cu" signal "IN1")
		(8 "In3.Cu" signal "GND1")
		(10 "In4.Cu" signal "IN2")
		(12 "In5.Cu" signal "GND2")
		(14 "In6.Cu" signal "IN3")
		(16 "In7.Cu" signal "GND3")
		(18 "In8.Cu" signal "VCC")
		(20 "In9.Cu" signal "VCC1")
		(22 "In10.Cu" signal "GND4")
		(24 "In11.Cu" signal "IN4")
		(26 "In12.Cu" signal "GND5")
		(28 "In13.Cu" signal "IN5")
		(30 "In14.Cu" signal "GND6")
		(32 "In15.Cu" signal "IN6")
		(34 "In16.Cu" signal "GND7")
		(2 "B.Cu" signal "BOTTOM")
		(9 "F.Adhes" user "F.Adhesive")
		(11 "B.Adhes" user "B.Adhesive")
		(13 "F.Paste" user "Package Geometry/Pastemask Top")
		(15 "B.Paste" user "Package Geometry/Pastemask Bottom")
		(5 "F.SilkS" user "Ref Des/Silkscreen Top")
		(7 "B.SilkS" user "Ref Des/Silkscreen Bottom")
		(1 "F.Mask" user "Board Geometry/Soldermask Top")
		(3 "B.Mask" user "Board Geometry/Soldermask Bottom")
		(17 "Dwgs.User" user "User.Drawings")
		(19 "Cmts.User" user "User.Comments")
		(21 "Eco1.User" user "User.Eco1")
		(23 "Eco2.User" user "User.Eco2")
		(25 "Edge.Cuts" user "Board Geometry/Outline")
		(27 "Margin" user)
		(31 "F.CrtYd" user "Package Geometry/Place Bound Top")
		(29 "B.CrtYd" user "Package Geometry/Place Bound Bottom")
		(35 "F.Fab" user "Ref Des/Assembly Top")
		(33 "B.Fab" user "Ref Des/Assembly Bottom")
	)
	(footprint ""
		(layer "F.Cu")
		(at 174.82566 -97.516188 90)
		(property "Reference" "R1330"
			(at 0 0 90)
			(layer "F.SilkS")
			(hide yes)
			(effects
				(font
					(size 1.27 1.27)
				)
			)
		)
		(property "Value" ""
			(at 0 0 90)
			(layer "F.Fab")
			(effects
				(font
					(size 1.27 1.27)
				)
			)
		)
		(duplicate_pad_numbers_are_jumpers no)
		(fp_line
			(start 0.7874 -0.4064)
			(end 0.7874 0.4064)
			(stroke
				(width 0.1524)
				(type default)
			)
			(layer "F.SilkS")
		)
		(fp_line
			(start -0.7874 -0.4064)
			(end 0.7874 -0.4064)
			(stroke
				(width 0.1524)
				(type default)
			)
			(layer "F.SilkS")
		)
		(fp_line
			(start 0.7874 0.4064)
			(end -0.7874 0.4064)
			(stroke
				(width 0.1524)
				(type default)
			)
			(layer "F.SilkS")
		)
		(fp_line
			(start -0.7874 0.4064)
			(end -0.7874 -0.4064)
			(stroke
				(width 0.1524)
				(type default)
			)
			(layer "F.SilkS")
		)
		(fp_line
			(start -0.12065 -0.305054)
			(end -0.12065 -0.2794)
			(stroke
				(width 0.1)
				(type default)
			)
			(layer "F.Fab")
		)
		(fp_line
			(start -0.67945 -0.305054)
			(end -0.12065 -0.305054)
			(stroke
				(width 0.1)
				(type default)
			)
			(layer "F.Fab")
		)
		(fp_line
			(start 0.67945 -0.3048)
			(end 0.67945 0.3048)
			(stroke
				(width 0.1)
				(type default)
			)
			(layer "F.Fab")
		)
		(fp_line
			(start 0.12065 -0.3048)
			(end 0.67945 -0.3048)
			(stroke
				(width 0.1)
				(type default)
			)
			(layer "F.Fab")
		)
		(fp_line
			(start 0.12065 -0.2794)
			(end 0.12065 -0.3048)
			(stroke
				(width 0.1)
				(type default)
			)
			(layer "F.Fab")
		)
		(fp_line
			(start -0.12065 -0.2794)
			(end 0.12065 -0.2794)
			(stroke
				(width 0.1)
				(type default)
			)
			(layer "F.Fab")
		)
		(fp_line
			(start 0.120396 0.2794)
			(end -0.12065 0.2794)
			(stroke
				(width 0.1)
				(type default)
			)
			(layer "F.Fab")
		)
		(fp_line
			(start -0.12065 0.2794)
			(end -0.12065 0.3048)
			(stroke
				(width 0.1)
				(type default)
			)
			(layer "F.Fab")
		)
		(fp_line
			(start 0.67945 0.3048)
			(end 0.120396 0.3048)
			(stroke
				(width 0.1)
				(type default)
			)
			(layer "F.Fab")
		)
		(fp_line
			(start 0.120396 0.3048)
			(end 0.120396 0.2794)
			(stroke
				(width 0.1)
				(type default)
			)
			(layer "F.Fab")
		)
		(fp_line
			(start -0.12065 0.3048)
			(end -0.67945 0.3048)
			(stroke
				(width 0.1)
				(type default)
			)
			(layer "F.Fab")
		)
		(fp_line
			(start -0.67945 0.3048)
			(end -0.67945 -0.305054)
			(stroke
				(width 0.1)
				(type default)
			)
			(layer "F.Fab")
		)
		(pad "1" smd circle
			(at -0.40005 0 90)
			(size 0 0)
			(layers "F.Cu" "F.Mask" "F.Paste")
			(net "PWRGD_DRAMPWRGD_CPU1_CD_R_LVC1")
		)
		(pad "2" smd circle
			(at 0.40005 0 90)
			(size 0 0)
			(layers "F.Cu" "F.Mask" "F.Paste")
			(net "GND")
		)
	)
	(footprint ""
		(layer "F.Cu")
		(at 374.00484 -336.935572 -90)
		(property "Reference" "PC251_P0_5"
			(at 0 0 270)
			(layer "F.SilkS")
			(hide yes)
			(effects
				(font
					(size 1.27 1.27)
				)
			)
		)
		(property "Value" ""
			(at 0 0 270)
			(layer "F.Fab")
			(effects
				(font
					(size 1.27 1.27)
				)
			)
		)
		(duplicate_pad_numbers_are_jumpers no)
		(fp_line
			(start -0.7874 0.4064)
			(end -0.7874 -0.4064)
			(stroke
				(width 0.1524)
				(type default)
			)
			(layer "F.SilkS")
		)
		(fp_line
			(start 0.7874 0.4064)
			(end -0.7874 0.4064)
			(stroke
				(width 0.1524)
				(type default)
			)
			(layer "F.SilkS")
		)
		(fp_line
			(start -0.7874 -0.4064)
			(end 0.7874 -0.4064)
			(stroke
				(width 0.1524)
				(type default)
			)
			(layer "F.SilkS")
		)
		(fp_line
			(start 0.7874 -0.4064)
			(end 0.7874 0.4064)
			(stroke
				(width 0.1524)
				(type default)
			)
			(layer "F.SilkS")
		)
		(fp_line
			(start -0.67945 0.3048)
			(end -0.67945 -0.305054)
			(stroke
				(width 0.1)
				(type default)
			)
			(layer "F.Fab")
		)
		(fp_line
			(start -0.12065 0.3048)
			(end -0.67945 0.3048)
			(stroke
				(width 0.1)
				(type default)
			)
			(layer "F.Fab")
		)
		(fp_line
			(start 0.120396 0.3048)
			(end 0.120396 0.2794)
			(stroke
				(width 0.1)
				(type default)
			)
			(layer "F.Fab")
		)
		(fp_line
			(start 0.67945 0.3048)
			(end 0.120396 0.3048)
			(stroke
				(width 0.1)
				(type default)
			)
			(layer "F.Fab")
		)
		(fp_line
			(start -0.12065 0.2794)
			(end -0.12065 0.3048)
			(stroke
				(width 0.1)
				(type default)
			)
			(layer "F.Fab")
		)
		(fp_line
			(start 0.120396 0.2794)
			(end -0.12065 0.2794)
			(stroke
				(width 0.1)
				(type default)
			)
			(layer "F.Fab")
		)
		(fp_line
			(start -0.12065 -0.2794)
			(end 0.12065 -0.2794)
			(stroke
				(width 0.1)
				(type default)
			)
			(layer "F.Fab")
		)
		(fp_line
			(start 0.12065 -0.2794)
			(end 0.12065 -0.3048)
			(stroke
				(width 0.1)
				(type default)
			)
			(layer "F.Fab")
		)
		(fp_line
			(start 0.12065 -0.3048)
			(end 0.67945 -0.3048)
			(stroke
				(width 0.1)
				(type default)
			)
			(layer "F.Fab")
		)
		(fp_line
			(start 0.67945 -0.3048)
			(end 0.67945 0.3048)
			(stroke
				(width 0.1)
				(type default)
			)
			(layer "F.Fab")
		)
		(fp_line
			(start -0.67945 -0.305054)
			(end -0.12065 -0.305054)
			(stroke
				(width 0.1)
				(type default)
			)
			(layer "F.Fab")
		)
		(fp_line
			(start -0.12065 -0.305054)
			(end -0.12065 -0.2794)
			(stroke
				(width 0.1)
				(type default)
			)
			(layer "F.Fab")
		)
		(pad "1" smd circle
			(at -0.40005 0 270)
			(size 0 0)
			(layers "F.Cu" "F.Mask" "F.Paste")
			(net "PVCCIN_CPU0_PVCC")
		)
		(pad "2" smd circle
			(at 0.40005 0 270)
			(size 0 0)
			(layers "F.Cu" "F.Mask" "F.Paste")
			(net "GND")
		)
	)
)
